# SCM (Grand Teton) — schematic parts with pin connectivity, parts 1326–1360 of 1428; source: Cadence DE-HDL packaged netlist (pstxprt.dat, pstxnet.dat, pstchip.dat)

R866  Q_RES  10K 1% CHIP  pkg 0402LF  page 44 : 1 = FM_BMC_BIOS_MUX_CS_SPI_R_SEL_0 ; 2 = GND
R867  Q_RES  1K 1% EMPTY  pkg 0402LF  page 21 : 1 = P3V3_AUX ; 2 = EMMC_WP
R868  Q_RES  0 5% EMPTY  pkg 0402LF  page 51 : 1 = PWRGD_P5V_AUX_R ; 2 = EN_P3V3_R1
R869  Q_RES  0 5% EMPTY  pkg 0402LF  page 52 : 1 = PWRGD_P1V8_AUX_R3 ; 2 = EN_P3V3_RGM_R
R870  Q_RES  4.7K 1% EMPTY  pkg 0402LF  page 44 : 1 = P3V3_AUX ; 2 = PD_BIOS_MUX_EN_N
R871  Q_RES  0 5% EMPTY  pkg 0402LF  page 52 : 1 = EN_P3V3_R1 ; 2 = PWRGD_EN_P3V3_R
R872  Q_RES  0 5% EMPTY  pkg 0402LF  page 52 : 1 = PWRGD_P3V3_RGM_R ; 2 = PWRGD_P3V3_RGM_R3
R873  Q_RES  0 5% EMPTY  pkg 0402LF  page 53 : 1 = PWRGD_P2V5_AUX_R3 ; 2 = PWRGD_P2V5_AUX
R874  Q_RES  0 5% EMPTY  pkg 0402LF  page 54 : 1 = PWRGD_P1V8_AUX_R3 ; 2 = PWRGD_P1V8_AUX_R
R875  Q_RES  0 5% EMPTY  pkg 0402LF  page 54 : 1 = PWRGD_P2V5_AUX_R3 ; 2 = EN_P1V8_R
R876  Q_RES  0 5% EMPTY  pkg 0402LF  page 55 : 1 = PWRGD_P3V3_RGM_R3 ; 2 = EN_P1V2_AUX_R
R877  Q_RES  0 5% EMPTY  pkg 0402LF  page 55 : 1 = PWRGD_P1V2_AUX_R ; 2 = PWRGD_P1V2_AUX_R2
R878  Q_RES  0 5% EMPTY  pkg 0402LF  page 56 : 1 = PWRGD_P1V2_AUX_R2 ; 2 = EN_P1V0_AUX_R
R879  Q_RES  200 1% CHIP  pkg 0402LF  page 12 : 1 = SMB_BMC_MM16_R5_SCL ; 2 = SMB_BMC_MM16_SCL
R880  Q_RES  33.2 1% CHIP  pkg 0402LF  page 12 : 1 = SMB_BMC_MM16_R5_SDA ; 2 = SMB_BMC_MM16_SDA
R881  Q_RES  4.7K 1% EMPTY  pkg 0402LF  page 48 : 1 = P3V3_AUX ; 2 = FM_JTAG_TCK_MUX_BMC_SEL_R
R882  Q_RES  0 5% CHIP  pkg 0402LF  page 50 : 1 = REAR_AC_PWR_BTN ; 2 = REAR_AC_PWR_BMC_BTN_N
R883  Q_RES  8.2K 5% EMPTY  pkg 0402LF  page 50 : 1 = P3V3_AUX ; 2 = REAR_AC_PWR_BMC_BTN_N
R884  Q_RES  33.2 1% CHIP  pkg 0402LF  page 14 : 1 = AC_PWR_BMC_BTN_R_N ; 2 = AC_PWR_BMC_BTN_N
R885  Q_RES  4.7K 1% CHIP  pkg 0402LF  page 14 : 1 = P1V8_AUX ; 2 = AC_PWR_BMC_BTN_N
R886  Q_RES  4.7K 1% CHIP  pkg 0402LF  page 35 : 1 = P3V3_AUX ; 2 = PWRGD_P5V_AUX_R1
R887  Q_RES  4.7K 1% EMPTY  pkg 0402LF  page 22 : 1 = P3V3_AUX ; 2 = RST_BMC_HW
R888  Q_RES  1K 1% EMPTY  pkg 0402LF  page 22 : 1 = P3V3_AUX ; 2 = RST_BMC_SELF_HW
R898  Q_RES  0 5% CHIP  pkg 0402LF  page 36 : 1 = FM_UARTSW_LSB_R_N ; 2 = FM_UARTSW_LSB_N
R899  Q_RES  0 5% CHIP  pkg 0402LF  page 36 : 1 = FM_UARTSW_MSB_R_N ; 2 = FM_UARTSW_MSB_N
R900  Q_RES  0 5% CHIP  pkg 0402LF  page 31 : 1 = UART_BIC_DBG_TX ; 2 = UART_BIC_DBG_TX_R
R901  Q_RES  0 5% CHIP  pkg 0402LF  page 31 : 1 = UART_6_BMC_RXD ; 2 = UART_6_BMC_RXD_R
R902  Q_RES  0 5% CHIP  pkg 0402LF  page 31 : 1 = UART_BIC_DBG_RX ; 2 = UART_BIC_DBG_RX_R
R903  Q_RES  0 5% CHIP  pkg 0402LF  page 31 : 1 = UART_6_BMC_TXD ; 2 = UART_6_BMC_TXD_R

SW6  SW_PUSHBUTTON4P_12_G34_H2  SW4S_DTSAM-63N/K-S-Q-T/R MECH  pkg SW4S_DTSAM63N  page 50
  1  \1\  BI  = GND
  2  \2\  BI  = REAR_PWR_BTN_N
  3  \3\  BI  = GND
  4  \4\  BI  = GND

SW7  SW_PUSHBUTTON4P_12_G34_H2  SW4S_DTSAM-63N/K-S-Q-T/R MECH  pkg SW4S_DTSAM63N  page 50
  1  \1\  BI  = GND
  2  \2\  BI  = REAR_ID_RST_BTN_N
  3  \3\  BI  = GND
  4  \4\  BI  = GND

SW8  SW_PUSHBUTTON4P_12_G34_H2  SW4S_DTSAM-63N/K-S-Q-T/R MECH  pkg SW4S_DTSAM63N  page 50
  1  \1\  BI  = GND
  2  \2\  BI  = REAR_AC_PWR_BTN
  3  \3\  BI  = GND
  4  \4\  BI  = GND

U1  K4A8G165WCBCTD  K4A8G165WC-BCTD IC  pkg BGA96XB  page 20
  A1  VDDQ0  POWER  = P1V2_AUX
  A2  VSSQ0  POWER  = GND
  A3  DQU0  BI  = M_BMC_DDR4_DQ<8>
  A7  DQSU_C  BI  = M_BMC_DDR4_DQS1_N
  A8  VSSQ1  POWER  = GND
  A9  VDDQ1  POWER  = P1V2_AUX
  B1  VPP0  POWER  = P2V5_AUX
  B2  VSS0  POWER  = GND
  B3  VDD0  POWER  = P1V2_AUX
  B7  DQSU_T  BI  = M_BMC_DDR4_DQS1_P
  B8  DQU1  BI  = M_BMC_DDR4_DQ<9>
  B9  VDD1  POWER  = P1V2_AUX
  C1  VDDQ2  POWER  = P1V2_AUX
  C2  DQU4  BI  = M_BMC_DDR4_DQ<12>
  C3  DQU2  BI  = M_BMC_DDR4_DQ<10>
  C7  DQU3  BI  = M_BMC_DDR4_DQ<11>
  C8  DQU5  BI  = M_BMC_DDR4_DQ<13>
  C9  VSSQ2  POWER  = GND
  D1  VDD2  POWER  = P1V2_AUX
  D2  VSSQ3  POWER  = GND
  D3  DQU6  BI  = M_BMC_DDR4_DQ<14>
  D7  DQU7  BI  = M_BMC_DDR4_DQ<15>
  D8  VSSQ4  POWER  = GND
  D9  VDDQ3  POWER  = P1V2_AUX
  E1  VSS1  POWER  = GND
  E2  \dmu_n||dbiu_n\  BI  = M_BMC_DDR4_MDM1
  E3  VSSQ5  POWER  = GND
  E7  \dml_n||dbil_n\  BI  = M_BMC_DDR4_MDM0
  E8  VSSQ6  POWER  = GND
  E9  VSS2  POWER  = M_BMC_DDR4_ZQU
  F1  VSSQ7  POWER  = GND
  F2  VDDQ4  POWER  = P1V2_AUX
  F3  DQSL_C  BI  = M_BMC_DDR4_DQS0_N
  F7  DQL1  BI  = M_BMC_DDR4_DQ<1>
  F8  VDDQ5  POWER  = P1V2_AUX
  F9  ZQ  POWER  = PD_M_BMC_DDR4_ZQ
  G1  VDDQ6  POWER  = P1V2_AUX
  G2  DQL0  BI  = M_BMC_DDR4_DQ<0>
  G3  DQSL_T  BI  = M_BMC_DDR4_DQS0_P
  G7  VDD3  POWER  = P1V2_AUX
  G8  VSS3  POWER  = GND
  G9  VDDQ7  POWER  = P1V2_AUX
  H1  VSSQ8  POWER  = GND
  H2  DQL4  BI  = M_BMC_DDR4_DQ<4>
  H3  DQL2  BI  = M_BMC_DDR4_DQ<2>
  H7  DQL3  BI  = M_BMC_DDR4_DQ<3>
  H8  DQL5  BI  = M_BMC_DDR4_DQ<5>
  H9  VSSQ9  POWER  = GND
  J1  VDD4  POWER  = P1V2_AUX
  J2  VDDQ8  POWER  = P1V2_AUX
  J3  DQL6  BI  = M_BMC_DDR4_DQ<6>
  J7  DQL7  BI  = M_BMC_DDR4_DQ<7>
  J8  VDDQ9  POWER  = P1V2_AUX
  J9  VDD5  POWER  = P1V2_AUX
  K1  VSS4  POWER  = GND
  K2  CKE  IN  = M_BMC_DDR4_MCKE
  K3  ODT  IN  = M_BMC_DDR4_MODT
  K7  CK_T  IN  = M_BMC_DDR4_MCLK_DP
  K8  CK_C  IN  = M_BMC_DDR4_MCLK_DN
  K9  VSS5  POWER  = GND
  L1  VDD6  POWER  = P1V2_AUX
  L2  \we_n||a14\  IN  = M_BMC_DDR4_MWE_N
  L3  ACT_N  IN  = M_BMC_DDR4_MACT_N
  L7  CS_N  IN  = M_BMC_DDR4_MCS_N
  L8  RAS_N  IN  = M_BMC_DDR4_MRAS_N
  L9  VDD7  POWER  = P1V2_AUX
  M1  VREFCA  POWER  = P0V6_DDR_VREF_AUX
  M2  BG0  IN  = M_BMC_DDR4_MBG0
  M3  \a10||ap\  IN  = M_BMC_DDR4_MA<10>
  M7  \a12||bc_n\  IN  = M_BMC_DDR4_MA<12>
  M8  \cas_n||a15\  IN  = M_BMC_DDR4_MCAS_N
  M9  VSS6  POWER  = M_BMC_DDR4_BG1
  N1  VSS7  POWER  = GND
  N2  BA0  IN  = M_BMC_DDR4_MBA0
  N3  A4  IN  = M_BMC_DDR4_MA<4>
  N7  A3  IN  = M_BMC_DDR4_MA<3>
  N8  BA1  IN  = M_BMC_DDR4_MBA1
  N9  TEN  IN  = PD_M_BMC_DDR4_TEN
  P1  RESET_N  IN  = M_BMC_DDR4_RST_N
  P2  A6  IN  = M_BMC_DDR4_MA<6>
  P3  A0  IN  = M_BMC_DDR4_MA<0>
  P7  A1  IN  = M_BMC_DDR4_MA<1>
  P8  A5  IN  = M_BMC_DDR4_MA<5>
  P9  ALERT_N  BI  = M_BMC_DDR4_ALERT_N
  R1  VDD8  POWER  = P1V2_AUX
  R2  A8  IN  = M_BMC_DDR4_MA<8>
  R3  A2  IN  = M_BMC_DDR4_MA<2>
  R7  A9  IN  = M_BMC_DDR4_MA<9>
  R8  A7  IN  = M_BMC_DDR4_MA<7>
  R9  VPP1  POWER  = P2V5_AUX
  T1  VSS8  POWER  = GND
  T2  A11  IN  = M_BMC_DDR4_MA<11>
  T3  PAR  IN  = PD_M_BMC_DDR4_PAR
  T7  NC1  TRI  = GND
  T8  A13  IN  = M_BMC_DDR4_MA<13>
  T9  VDD9  POWER  = P1V2_AUX

U2  FSA3357K8X  IC  pkg US8_0-5_2X2-3_EOL  page 30
  1  B0  BI  = UART_BIC_DBG_TX
  2  B1  BI  = UART_BMC_5_TXD_BUF1_R
  3  B2  BI  = UART_BMC_1_TXD_R
  4  GND  POWER  = GND
  5  S2  IN  = FM_UARTSW_LSB_N
  6  S1  IN  = FM_UARTSW_MSB_N
  7  A  BI  = SPA_SOUT_SW_BUF
  8  VCC  POWER  = P3V3_AUX

U3  FSA3357K8X  IC  pkg US8_0-5_2X2-3_EOL  page 30
  1  B0  BI  = UART_BIC_DBG_RX
  2  B1  BI  = UART_BMC_5_RXD_BUF1_SW
  3  B2  BI  = UART_BMC_1_RXD_R
  4  GND  POWER  = GND
  5  S2  IN  = FM_UARTSW_LSB_N
  6  S1  IN  = FM_UARTSW_MSB_N
  7  A  BI  = SPA_SIN_SW_BUF
  8  VCC  POWER  = P3V3_AUX
